# S9S_MB_2U (Grand Teton) — schematic netlist excerpt (pin names and nets, part order shuffled) for the footprints in the layout excerpt that follows; sources: Cadence DE-HDL packaged netlist, KiCad conversion of 03242023_DA0F0TMBIJ0_F0T_Motherboard_J_brd_V01_OCP.brd

C467  Q_CAP  47UF 4V 20% X6S  pkg C0805  page 79 : A = PVCCD_HV_CPU1 ; B = GND
PR1307  Q_RES  2.2 1% CHIP  pkg 0402LF  page 290 : A = PVCCFA_EHV_FIVRA_CPU1_PVCC2 ; B = PVCCFA_EHV_FIVRA_CPU1_VDD4
PC533_P1_4  Q_CAP  22UF 16V 20% X6S  pkg C0805  page 286 : A = SW_P12V_PVCCIN_CPU1_FLT ; B = GND

(kicad_pcb
	(version 20260206)
	(generator "pcbnew")
	(generator_version "10.0")
	(general
		(thickness 1.6)
		(legacy_teardrops no)
	)
	(paper "A4")
	(title_block
		(title "03242023_DA0F0TMBIJ0_F0T_Motherboard_J_brd_V01_OCP.brd")
		(comment 1 "Grand Teton / footprints 4326-4328 of 6105")
	)
	(layers
		(0 "F.Cu" signal "TOP")
		(4 "In1.Cu" signal "GND")
		(6 "In2.Cu" signal "IN1")
		(8 "In3.Cu" signal "GND1")
		(10 "In4.Cu" signal "IN2")
		(12 "In5.Cu" signal "GND2")
		(14 "In6.Cu" signal "IN3")
		(16 "In7.Cu" signal "GND3")
		(18 "In8.Cu" signal "VCC")
		(20 "In9.Cu" signal "VCC1")
		(22 "In10.Cu" signal "GND4")
		(24 "In11.Cu" signal "IN4")
		(26 "In12.Cu" signal "GND5")
		(28 "In13.Cu" signal "IN5")
		(30 "In14.Cu" signal "GND6")
		(32 "In15.Cu" signal "IN6")
		(34 "In16.Cu" signal "GND7")
		(2 "B.Cu" signal "BOTTOM")
		(9 "F.Adhes" user "F.Adhesive")
		(11 "B.Adhes" user "B.Adhesive")
		(13 "F.Paste" user "Package Geometry/Pastemask Top")
		(15 "B.Paste" user "Package Geometry/Pastemask Bottom")
		(5 "F.SilkS" user "Ref Des/Silkscreen Top")
		(7 "B.SilkS" user "Ref Des/Silkscreen Bottom")
		(1 "F.Mask" user "Board Geometry/Soldermask Top")
		(3 "B.Mask" user "Board Geometry/Soldermask Bottom")
		(17 "Dwgs.User" user "User.Drawings")
		(19 "Cmts.User" user "User.Comments")
		(21 "Eco1.User" user "User.Eco1")
		(23 "Eco2.User" user "User.Eco2")
		(25 "Edge.Cuts" user "Board Geometry/Outline")
		(27 "Margin" user)
		(31 "F.CrtYd" user "Package Geometry/Place Bound Top")
		(29 "B.CrtYd" user "Package Geometry/Place Bound Bottom")
		(35 "F.Fab" user "Ref Des/Assembly Top")
		(33 "B.Fab" user "Ref Des/Assembly Bottom")
	)
	(footprint ""
		(layer "B.Cu")
		(at 39.062406 -354.565204 -90)
		(property "Reference" "PR1307"
			(at 0 0 90)
			(layer "B.SilkS")
			(hide yes)
			(effects
				(font
					(size 1.27 1.27)
				)
				(justify mirror)
			)
		)
		(property "Value" ""
			(at 0 0 90)
			(layer "B.Fab")
			(effects
				(font
					(size 1.27 1.27)
				)
				(justify mirror)
			)
		)
		(duplicate_pad_numbers_are_jumpers no)
		(fp_line
			(start -0.7874 0.4064)
			(end 0.7874 0.4064)
			(stroke
				(width 0.1524)
				(type default)
			)
			(layer "B.SilkS")
		)
		(fp_line
			(start 0.7874 0.4064)
			(end 0.7874 -0.4064)
			(stroke
				(width 0.1524)
				(type default)
			)
			(layer "B.SilkS")
		)
		(fp_line
			(start -0.7874 -0.4064)
			(end -0.7874 0.4064)
			(stroke
				(width 0.1524)
				(type default)
			)
			(layer "B.SilkS")
		)
		(fp_line
			(start 0.7874 -0.4064)
			(end -0.7874 -0.4064)
			(stroke
				(width 0.1524)
				(type default)
			)
			(layer "B.SilkS")
		)
		(fp_line
			(start -0.67945 0.3048)
			(end -0.120396 0.3048)
			(stroke
				(width 0.1)
				(type default)
			)
			(layer "B.Fab")
		)
		(fp_line
			(start -0.120396 0.3048)
			(end -0.120396 0.2794)
			(stroke
				(width 0.1)
				(type default)
			)
			(layer "B.Fab")
		)
		(fp_line
			(start 0.12065 0.3048)
			(end 0.67945 0.3048)
			(stroke
				(width 0.1)
				(type default)
			)
			(layer "B.Fab")
		)
		(fp_line
			(start 0.67945 0.3048)
			(end 0.67945 -0.305054)
			(stroke
				(width 0.1)
				(type default)
			)
			(layer "B.Fab")
		)
		(fp_line
			(start -0.120396 0.2794)
			(end 0.12065 0.2794)
			(stroke
				(width 0.1)
				(type default)
			)
			(layer "B.Fab")
		)
		(fp_line
			(start 0.12065 0.2794)
			(end 0.12065 0.3048)
			(stroke
				(width 0.1)
				(type default)
			)
			(layer "B.Fab")
		)
		(fp_line
			(start -0.12065 -0.2794)
			(end -0.12065 -0.3048)
			(stroke
				(width 0.1)
				(type default)
			)
			(layer "B.Fab")
		)
		(fp_line
			(start 0.12065 -0.2794)
			(end -0.12065 -0.2794)
			(stroke
				(width 0.1)
				(type default)
			)
			(layer "B.Fab")
		)
		(fp_line
			(start -0.67945 -0.3048)
			(end -0.67945 0.3048)
			(stroke
				(width 0.1)
				(type default)
			)
			(layer "B.Fab")
		)
		(fp_line
			(start -0.12065 -0.3048)
			(end -0.67945 -0.3048)
			(stroke
				(width 0.1)
				(type default)
			)
			(layer "B.Fab")
		)
		(fp_line
			(start 0.12065 -0.305054)
			(end 0.12065 -0.2794)
			(stroke
				(width 0.1)
				(type default)
			)
			(layer "B.Fab")
		)
		(fp_line
			(start 0.67945 -0.305054)
			(end 0.12065 -0.305054)
			(stroke
				(width 0.1)
				(type default)
			)
			(layer "B.Fab")
		)
		(pad "1" smd circle
			(at 0.40005 0 90)
			(size 0 0)
			(layers "B.Cu" "B.Mask" "B.Paste")
			(net "PVCCFA_EHV_FIVRA_CPU1_PVCC2")
		)
		(pad "2" smd circle
			(at -0.40005 0 90)
			(size 0 0)
			(layers "B.Cu" "B.Mask" "B.Paste")
			(net "PVCCFA_EHV_FIVRA_CPU1_VDD4")
		)
	)
	(footprint ""
		(layer "B.Cu")
		(at 114.734086 -212.049868 180)
		(property "Reference" "C467"
			(at 0 0 0)
			(layer "B.SilkS")
			(hide yes)
			(effects
				(font
					(size 1.27 1.27)
				)
				(justify mirror)
			)
		)
		(property "Value" ""
			(at 0 0 0)
			(layer "B.Fab")
			(effects
				(font
					(size 1.27 1.27)
				)
				(justify mirror)
			)
		)
		(duplicate_pad_numbers_are_jumpers no)
		(fp_line
			(start 1.524 0.762)
			(end 1.524 -0.762)
			(stroke
				(width 0.1524)
				(type default)
			)
			(layer "B.SilkS")
		)
		(fp_line
			(start 1.524 -0.762)
			(end -1.524 -0.762)
			(stroke
				(width 0.1524)
				(type default)
			)
			(layer "B.SilkS")
		)
		(fp_line
			(start -1.524 0.762)
			(end 1.524 0.762)
			(stroke
				(width 0.1524)
				(type default)
			)
			(layer "B.SilkS")
		)
		(fp_line
			(start -1.524 -0.762)
			(end -1.524 0.762)
			(stroke
				(width 0.1524)
				(type default)
			)
			(layer "B.SilkS")
		)
		(fp_line
			(start 1.1049 0.724916)
			(end -1.1049 0.724916)
			(stroke
				(width 0.1)
				(type default)
			)
			(layer "B.Fab")
		)
		(fp_line
			(start 1.1049 -0.724916)
			(end 1.1049 0.724916)
			(stroke
				(width 0.1)
				(type default)
			)
			(layer "B.Fab")
		)
		(fp_line
			(start -1.1049 0.724916)
			(end -1.1049 -0.724916)
			(stroke
				(width 0.1)
				(type default)
			)
			(layer "B.Fab")
		)
		(fp_line
			(start -1.1049 -0.724916)
			(end 1.1049 -0.724916)
			(stroke
				(width 0.1)
				(type default)
			)
			(layer "B.Fab")
		)
		(pad "1" smd rect
			(at 0.889 0 180)
			(size 1.016 1.27)
			(layers "B.Cu" "B.Mask" "B.Paste")
			(net "PVCCD_HV_CPU1")
		)
		(pad "2" smd rect
			(at -0.889 0 180)
			(size 1.016 1.27)
			(layers "B.Cu" "B.Mask" "B.Paste")
			(net "GND")
		)
	)
	(footprint ""
		(layer "B.Cu")
		(at 122.794268 -337.546442 -90)
		(property "Reference" "PC533_P1_4"
			(at 0 0 90)
			(layer "B.SilkS")
			(hide yes)
			(effects
				(font
					(size 1.27 1.27)
				)
				(justify mirror)
			)
		)
		(property "Value" ""
			(at 0 0 90)
			(layer "B.Fab")
			(effects
				(font
					(size 1.27 1.27)
				)
				(justify mirror)
			)
		)
		(duplicate_pad_numbers_are_jumpers no)
		(fp_line
			(start -1.524 0.762)
			(end 1.524 0.762)
			(stroke
				(width 0.1524)
				(type default)
			)
			(layer "B.SilkS")
		)
		(fp_line
			(start 1.524 0.762)
			(end 1.524 -0.762)
			(stroke
				(width 0.1524)
				(type default)
			)
			(layer "B.SilkS")
		)
		(fp_line
			(start -1.524 -0.762)
			(end -1.524 0.762)
			(stroke
				(width 0.1524)
				(type default)
			)
			(layer "B.SilkS")
		)
		(fp_line
			(start 1.524 -0.762)
			(end -1.524 -0.762)
			(stroke
				(width 0.1524)
				(type default)
			)
			(layer "B.SilkS")
		)
		(fp_line
			(start -1.1049 0.724916)
			(end -1.1049 -0.724916)
			(stroke
				(width 0.1)
				(type default)
			)
			(layer "B.Fab")
		)
		(fp_line
			(start 1.1049 0.724916)
			(end -1.1049 0.724916)
			(stroke
				(width 0.1)
				(type default)
			)
			(layer "B.Fab")
		)
		(fp_line
			(start -1.1049 -0.724916)
			(end 1.1049 -0.724916)
			(stroke
				(width 0.1)
				(type default)
			)
			(layer "B.Fab")
		)
		(fp_line
			(start 1.1049 -0.724916)
			(end 1.1049 0.724916)
			(stroke
				(width 0.1)
				(type default)
			)
			(layer "B.Fab")
		)
		(pad "1" smd rect
			(at 0.889 0 270)
			(size 1.016 1.27)
			(layers "B.Cu" "B.Mask" "B.Paste")
			(net "SW_P12V_PVCCIN_CPU1_FLT")
		)
		(pad "2" smd rect
			(at -0.889 0 270)
			(size 1.016 1.27)
			(layers "B.Cu" "B.Mask" "B.Paste")
			(net "GND")
		)
	)
)
